# T6G (Grand Teton) — schematic netlist excerpt (pin names and nets, part order shuffled) for the footprints in the layout excerpt that follows; sources: Cadence DE-HDL packaged netlist, KiCad conversion of 04192023_DAF0TMB3IC0_F0TG_MB_C_brd_V02_OCP.brd

PC188_4  Q_CAP  22UF 16V 20% X6S  pkg C0805  page 206 : A = SW_P12V_AUX_PVDDIO_P0_FLT ; B = GND
R6121  Q_RES  1K 1% EMPTY  pkg 0402LF  page 84 : A = PVDD18_S5_P0 ; B = FM_BOARD_SKU_ID3
R375  Q_RES  15 1% CHIP  pkg 0402LF  page 10 : A = M_A_CPU0_ALERT_N ; B = M_A_CPU0_ALERT_R_N

(kicad_pcb
	(version 20260206)
	(generator "pcbnew")
	(generator_version "10.0")
	(general
		(thickness 1.6)
		(legacy_teardrops no)
	)
	(paper "A4")
	(title_block
		(title "04192023_DAF0TMB3IC0_F0TG_MB_C_brd_V02_OCP.brd")
		(comment 1 "Grand Teton / footprints 6054-6056 of 8354")
	)
	(layers
		(0 "F.Cu" signal "TOP")
		(4 "In1.Cu" signal "GND")
		(6 "In2.Cu" signal "IN1")
		(8 "In3.Cu" signal "GND1")
		(10 "In4.Cu" signal "IN2")
		(12 "In5.Cu" signal "GND2")
		(14 "In6.Cu" signal "IN3")
		(16 "In7.Cu" signal "GND3")
		(18 "In8.Cu" signal "VCC")
		(20 "In9.Cu" signal "VCC1")
		(22 "In10.Cu" signal "GND4")
		(24 "In11.Cu" signal "IN4")
		(26 "In12.Cu" signal "GND5")
		(28 "In13.Cu" signal "IN5")
		(30 "In14.Cu" signal "GND6")
		(32 "In15.Cu" signal "IN6")
		(34 "In16.Cu" signal "GND7")
		(2 "B.Cu" signal "BOTTOM")
		(9 "F.Adhes" user "F.Adhesive")
		(11 "B.Adhes" user "B.Adhesive")
		(13 "F.Paste" user "Package Geometry/Pastemask Top")
		(15 "B.Paste" user "Package Geometry/Pastemask Bottom")
		(5 "F.SilkS" user "Ref Des/Silkscreen Top")
		(7 "B.SilkS" user "Ref Des/Silkscreen Bottom")
		(1 "F.Mask" user "Board Geometry/Soldermask Top")
		(3 "B.Mask" user "Board Geometry/Soldermask Bottom")
		(17 "Dwgs.User" user "User.Drawings")
		(19 "Cmts.User" user "User.Comments")
		(21 "Eco1.User" user "User.Eco1")
		(23 "Eco2.User" user "User.Eco2")
		(25 "Edge.Cuts" user "Board Geometry/Outline")
		(27 "Margin" user)
		(31 "F.CrtYd" user "Package Geometry/Place Bound Top")
		(29 "B.CrtYd" user "Package Geometry/Place Bound Bottom")
		(35 "F.Fab" user "Ref Des/Assembly Top")
		(33 "B.Fab" user "Ref Des/Assembly Bottom")
	)
	(footprint ""
		(layer "B.Cu")
		(at 276.54377 -350.65589 -90)
		(property "Reference" "PC188_4"
			(at 0 0 90)
			(layer "B.SilkS")
			(hide yes)
			(effects
				(font
					(size 1.27 1.27)
				)
				(justify mirror)
			)
		)
		(property "Value" ""
			(at 0 0 90)
			(layer "B.Fab")
			(effects
				(font
					(size 1.27 1.27)
				)
				(justify mirror)
			)
		)
		(duplicate_pad_numbers_are_jumpers no)
		(fp_line
			(start -1.524 0.762)
			(end 1.524 0.762)
			(stroke
				(width 0.1524)
				(type default)
			)
			(layer "B.SilkS")
		)
		(fp_line
			(start 1.524 0.762)
			(end 1.524 -0.762)
			(stroke
				(width 0.1524)
				(type default)
			)
			(layer "B.SilkS")
		)
		(fp_line
			(start -1.524 -0.762)
			(end -1.524 0.762)
			(stroke
				(width 0.1524)
				(type default)
			)
			(layer "B.SilkS")
		)
		(fp_line
			(start 1.524 -0.762)
			(end -1.524 -0.762)
			(stroke
				(width 0.1524)
				(type default)
			)
			(layer "B.SilkS")
		)
		(fp_line
			(start -1.1049 0.724916)
			(end -1.1049 -0.724916)
			(stroke
				(width 0.1)
				(type default)
			)
			(layer "B.Fab")
		)
		(fp_line
			(start 1.1049 0.724916)
			(end -1.1049 0.724916)
			(stroke
				(width 0.1)
				(type default)
			)
			(layer "B.Fab")
		)
		(fp_line
			(start -1.1049 -0.724916)
			(end 1.1049 -0.724916)
			(stroke
				(width 0.1)
				(type default)
			)
			(layer "B.Fab")
		)
		(fp_line
			(start 1.1049 -0.724916)
			(end 1.1049 0.724916)
			(stroke
				(width 0.1)
				(type default)
			)
			(layer "B.Fab")
		)
		(pad "1" smd rect
			(at 0.889 0 270)
			(size 1.016 1.27)
			(layers "B.Cu" "B.Mask" "B.Paste")
			(net "SW_P12V_AUX_PVDDIO_P0_FLT")
		)
		(pad "2" smd rect
			(at -0.889 0 270)
			(size 1.016 1.27)
			(layers "B.Cu" "B.Mask" "B.Paste")
			(net "GND")
		)
	)
	(footprint ""
		(layer "B.Cu")
		(at 404.043642 -349.215964 -90)
		(property "Reference" "R6121"
			(at 0 0 90)
			(layer "B.SilkS")
			(hide yes)
			(effects
				(font
					(size 1.27 1.27)
				)
				(justify mirror)
			)
		)
		(property "Value" ""
			(at 0 0 90)
			(layer "B.Fab")
			(effects
				(font
					(size 1.27 1.27)
				)
				(justify mirror)
			)
		)
		(duplicate_pad_numbers_are_jumpers no)
		(fp_line
			(start -0.7874 0.4064)
			(end 0.7874 0.4064)
			(stroke
				(width 0.1524)
				(type default)
			)
			(layer "B.SilkS")
		)
		(fp_line
			(start 0.7874 0.4064)
			(end 0.7874 -0.4064)
			(stroke
				(width 0.1524)
				(type default)
			)
			(layer "B.SilkS")
		)
		(fp_line
			(start -0.7874 -0.4064)
			(end -0.7874 0.4064)
			(stroke
				(width 0.1524)
				(type default)
			)
			(layer "B.SilkS")
		)
		(fp_line
			(start 0.7874 -0.4064)
			(end -0.7874 -0.4064)
			(stroke
				(width 0.1524)
				(type default)
			)
			(layer "B.SilkS")
		)
		(fp_line
			(start -0.67945 0.3048)
			(end -0.120396 0.3048)
			(stroke
				(width 0.1)
				(type default)
			)
			(layer "B.Fab")
		)
		(fp_line
			(start -0.120396 0.3048)
			(end -0.120396 0.2794)
			(stroke
				(width 0.1)
				(type default)
			)
			(layer "B.Fab")
		)
		(fp_line
			(start 0.12065 0.3048)
			(end 0.67945 0.3048)
			(stroke
				(width 0.1)
				(type default)
			)
			(layer "B.Fab")
		)
		(fp_line
			(start 0.67945 0.3048)
			(end 0.67945 -0.305054)
			(stroke
				(width 0.1)
				(type default)
			)
			(layer "B.Fab")
		)
		(fp_line
			(start -0.120396 0.2794)
			(end 0.12065 0.2794)
			(stroke
				(width 0.1)
				(type default)
			)
			(layer "B.Fab")
		)
		(fp_line
			(start 0.12065 0.2794)
			(end 0.12065 0.3048)
			(stroke
				(width 0.1)
				(type default)
			)
			(layer "B.Fab")
		)
		(fp_line
			(start -0.12065 -0.2794)
			(end -0.12065 -0.3048)
			(stroke
				(width 0.1)
				(type default)
			)
			(layer "B.Fab")
		)
		(fp_line
			(start 0.12065 -0.2794)
			(end -0.12065 -0.2794)
			(stroke
				(width 0.1)
				(type default)
			)
			(layer "B.Fab")
		)
		(fp_line
			(start -0.67945 -0.3048)
			(end -0.67945 0.3048)
			(stroke
				(width 0.1)
				(type default)
			)
			(layer "B.Fab")
		)
		(fp_line
			(start -0.12065 -0.3048)
			(end -0.67945 -0.3048)
			(stroke
				(width 0.1)
				(type default)
			)
			(layer "B.Fab")
		)
		(fp_line
			(start 0.12065 -0.305054)
			(end 0.12065 -0.2794)
			(stroke
				(width 0.1)
				(type default)
			)
			(layer "B.Fab")
		)
		(fp_line
			(start 0.67945 -0.305054)
			(end 0.12065 -0.305054)
			(stroke
				(width 0.1)
				(type default)
			)
			(layer "B.Fab")
		)
		(pad "1" smd circle
			(at 0.40005 0 90)
			(size 0 0)
			(layers "B.Cu" "B.Mask" "B.Paste")
			(net "PVDD18_S5_P0")
		)
		(pad "2" smd circle
			(at -0.40005 0 90)
			(size 0 0)
			(layers "B.Cu" "B.Mask" "B.Paste")
			(net "FM_BOARD_SKU_ID3")
		)
	)
	(footprint ""
		(layer "B.Cu")
		(at 306.135278 -244.08511)
		(property "Reference" "R375"
			(at 0 0 0)
			(layer "B.SilkS")
			(hide yes)
			(effects
				(font
					(size 1.27 1.27)
				)
				(justify mirror)
			)
		)
		(property "Value" ""
			(at 0 0 0)
			(layer "B.Fab")
			(effects
				(font
					(size 1.27 1.27)
				)
				(justify mirror)
			)
		)
		(duplicate_pad_numbers_are_jumpers no)
		(fp_line
			(start -0.7874 -0.4064)
			(end -0.7874 0.4064)
			(stroke
				(width 0.1524)
				(type default)
			)
			(layer "B.SilkS")
		)
		(fp_line
			(start -0.7874 0.4064)
			(end 0.7874 0.4064)
			(stroke
				(width 0.1524)
				(type default)
			)
			(layer "B.SilkS")
		)
		(fp_line
			(start 0.7874 -0.4064)
			(end -0.7874 -0.4064)
			(stroke
				(width 0.1524)
				(type default)
			)
			(layer "B.SilkS")
		)
		(fp_line
			(start 0.7874 0.4064)
			(end 0.7874 -0.4064)
			(stroke
				(width 0.1524)
				(type default)
			)
			(layer "B.SilkS")
		)
		(fp_line
			(start -0.67945 -0.3048)
			(end -0.67945 0.3048)
			(stroke
				(width 0.1)
				(type default)
			)
			(layer "B.Fab")
		)
		(fp_line
			(start -0.67945 0.3048)
			(end -0.120396 0.3048)
			(stroke
				(width 0.1)
				(type default)
			)
			(layer "B.Fab")
		)
		(fp_line
			(start -0.12065 -0.3048)
			(end -0.67945 -0.3048)
			(stroke
				(width 0.1)
				(type default)
			)
			(layer "B.Fab")
		)
		(fp_line
			(start -0.12065 -0.2794)
			(end -0.12065 -0.3048)
			(stroke
				(width 0.1)
				(type default)
			)
			(layer "B.Fab")
		)
		(fp_line
			(start -0.120396 0.2794)
			(end 0.12065 0.2794)
			(stroke
				(width 0.1)
				(type default)
			)
			(layer "B.Fab")
		)
		(fp_line
			(start -0.120396 0.3048)
			(end -0.120396 0.2794)
			(stroke
				(width 0.1)
				(type default)
			)
			(layer "B.Fab")
		)
		(fp_line
			(start 0.12065 -0.305054)
			(end 0.12065 -0.2794)
			(stroke
				(width 0.1)
				(type default)
			)
			(layer "B.Fab")
		)
		(fp_line
			(start 0.12065 -0.2794)
			(end -0.12065 -0.2794)
			(stroke
				(width 0.1)
				(type default)
			)
			(layer "B.Fab")
		)
		(fp_line
			(start 0.12065 0.2794)
			(end 0.12065 0.3048)
			(stroke
				(width 0.1)
				(type default)
			)
			(layer "B.Fab")
		)
		(fp_line
			(start 0.12065 0.3048)
			(end 0.67945 0.3048)
			(stroke
				(width 0.1)
				(type default)
			)
			(layer "B.Fab")
		)
		(fp_line
			(start 0.67945 -0.305054)
			(end 0.12065 -0.305054)
			(stroke
				(width 0.1)
				(type default)
			)
			(layer "B.Fab")
		)
		(fp_line
			(start 0.67945 0.3048)
			(end 0.67945 -0.305054)
			(stroke
				(width 0.1)
				(type default)
			)
			(layer "B.Fab")
		)
		(pad "1" smd circle
			(at 0.40005 0 180)
			(size 0 0)
			(layers "B.Cu" "B.Mask" "B.Paste")
			(net "M_A_CPU0_ALERT_N")
		)
		(pad "2" smd circle
			(at -0.40005 0 180)
			(size 0 0)
			(layers "B.Cu" "B.Mask" "B.Paste")
			(net "M_A_CPU0_ALERT_R_N")
		)
	)
)
